# T6G (Grand Teton) — schematic netlist excerpt (pin names and nets, part order shuffled) for the footprints in the layout excerpt that follows; sources: Cadence DE-HDL packaged netlist, KiCad conversion of 04192023_DAF0TMB3IC0_F0TG_MB_C_brd_V02_OCP.brd

C2636  Q_CAP  22UF 4V 20% X6S  pkg C0402  page 70 : A = PVDD11_S3_P0 ; B = GND
C2583  Q_CAP  22UF 4V 20% X6S  pkg C0402  page 70 : A = PVDDCR_SOC_P0 ; B = GND

(kicad_pcb
	(version 20260206)
	(generator "pcbnew")
	(generator_version "10.0")
	(general
		(thickness 1.6)
		(legacy_teardrops no)
	)
	(paper "A4")
	(title_block
		(title "04192023_DAF0TMB3IC0_F0TG_MB_C_brd_V02_OCP.brd")
		(comment 1 "Grand Teton / footprints 7330-7331 of 8354")
	)
	(layers
		(0 "F.Cu" signal "TOP")
		(4 "In1.Cu" signal "GND")
		(6 "In2.Cu" signal "IN1")
		(8 "In3.Cu" signal "GND1")
		(10 "In4.Cu" signal "IN2")
		(12 "In5.Cu" signal "GND2")
		(14 "In6.Cu" signal "IN3")
		(16 "In7.Cu" signal "GND3")
		(18 "In8.Cu" signal "VCC")
		(20 "In9.Cu" signal "VCC1")
		(22 "In10.Cu" signal "GND4")
		(24 "In11.Cu" signal "IN4")
		(26 "In12.Cu" signal "GND5")
		(28 "In13.Cu" signal "IN5")
		(30 "In14.Cu" signal "GND6")
		(32 "In15.Cu" signal "IN6")
		(34 "In16.Cu" signal "GND7")
		(2 "B.Cu" signal "BOTTOM")
		(9 "F.Adhes" user "F.Adhesive")
		(11 "B.Adhes" user "B.Adhesive")
		(13 "F.Paste" user "Package Geometry/Pastemask Top")
		(15 "B.Paste" user "Package Geometry/Pastemask Bottom")
		(5 "F.SilkS" user "Ref Des/Silkscreen Top")
		(7 "B.SilkS" user "Ref Des/Silkscreen Bottom")
		(1 "F.Mask" user "Board Geometry/Soldermask Top")
		(3 "B.Mask" user "Board Geometry/Soldermask Bottom")
		(17 "Dwgs.User" user "User.Drawings")
		(19 "Cmts.User" user "User.Comments")
		(21 "Eco1.User" user "User.Eco1")
		(23 "Eco2.User" user "User.Eco2")
		(25 "Edge.Cuts" user "Board Geometry/Outline")
		(27 "Margin" user)
		(31 "F.CrtYd" user "Package Geometry/Place Bound Top")
		(29 "B.CrtYd" user "Package Geometry/Place Bound Bottom")
		(35 "F.Fab" user "Ref Des/Assembly Top")
		(33 "B.Fab" user "Ref Des/Assembly Bottom")
	)
	(footprint ""
		(layer "B.Cu")
		(at 360.367072 -261.747762 90)
		(property "Reference" "C2636"
			(at 0 0 90)
			(layer "B.SilkS")
			(hide yes)
			(effects
				(font
					(size 1.27 1.27)
				)
				(justify mirror)
			)
		)
		(property "Value" ""
			(at 0 0 90)
			(layer "B.Fab")
			(effects
				(font
					(size 1.27 1.27)
				)
				(justify mirror)
			)
		)
		(duplicate_pad_numbers_are_jumpers no)
		(fp_line
			(start 0.7874 -0.4064)
			(end -0.7874 -0.4064)
			(stroke
				(width 0.1524)
				(type default)
			)
			(layer "B.SilkS")
		)
		(fp_line
			(start -0.7874 -0.4064)
			(end -0.7874 0.4064)
			(stroke
				(width 0.1524)
				(type default)
			)
			(layer "B.SilkS")
		)
		(fp_line
			(start 0.7874 0.4064)
			(end 0.7874 -0.4064)
			(stroke
				(width 0.1524)
				(type default)
			)
			(layer "B.SilkS")
		)
		(fp_line
			(start -0.7874 0.4064)
			(end 0.7874 0.4064)
			(stroke
				(width 0.1524)
				(type default)
			)
			(layer "B.SilkS")
		)
		(fp_line
			(start 0.67945 -0.305054)
			(end 0.12065 -0.305054)
			(stroke
				(width 0.1)
				(type default)
			)
			(layer "B.Fab")
		)
		(fp_line
			(start 0.12065 -0.305054)
			(end 0.12065 -0.2794)
			(stroke
				(width 0.1)
				(type default)
			)
			(layer "B.Fab")
		)
		(fp_line
			(start -0.12065 -0.3048)
			(end -0.67945 -0.3048)
			(stroke
				(width 0.1)
				(type default)
			)
			(layer "B.Fab")
		)
		(fp_line
			(start -0.67945 -0.3048)
			(end -0.67945 0.3048)
			(stroke
				(width 0.1)
				(type default)
			)
			(layer "B.Fab")
		)
		(fp_line
			(start 0.12065 -0.2794)
			(end -0.12065 -0.2794)
			(stroke
				(width 0.1)
				(type default)
			)
			(layer "B.Fab")
		)
		(fp_line
			(start -0.12065 -0.2794)
			(end -0.12065 -0.3048)
			(stroke
				(width 0.1)
				(type default)
			)
			(layer "B.Fab")
		)
		(fp_line
			(start 0.12065 0.2794)
			(end 0.12065 0.3048)
			(stroke
				(width 0.1)
				(type default)
			)
			(layer "B.Fab")
		)
		(fp_line
			(start -0.120396 0.2794)
			(end 0.12065 0.2794)
			(stroke
				(width 0.1)
				(type default)
			)
			(layer "B.Fab")
		)
		(fp_line
			(start 0.67945 0.3048)
			(end 0.67945 -0.305054)
			(stroke
				(width 0.1)
				(type default)
			)
			(layer "B.Fab")
		)
		(fp_line
			(start 0.12065 0.3048)
			(end 0.67945 0.3048)
			(stroke
				(width 0.1)
				(type default)
			)
			(layer "B.Fab")
		)
		(fp_line
			(start -0.120396 0.3048)
			(end -0.120396 0.2794)
			(stroke
				(width 0.1)
				(type default)
			)
			(layer "B.Fab")
		)
		(fp_line
			(start -0.67945 0.3048)
			(end -0.120396 0.3048)
			(stroke
				(width 0.1)
				(type default)
			)
			(layer "B.Fab")
		)
		(pad "1" smd circle
			(at 0.40005 0 270)
			(size 0 0)
			(layers "B.Cu" "B.Mask" "B.Paste")
			(net "PVDD11_S3_P0")
		)
		(pad "2" smd circle
			(at -0.40005 0 270)
			(size 0 0)
			(layers "B.Cu" "B.Mask" "B.Paste")
			(net "GND")
		)
	)
	(footprint ""
		(layer "B.Cu")
		(at 373.329454 -257.930142)
		(property "Reference" "C2583"
			(at 0 0 0)
			(layer "B.SilkS")
			(hide yes)
			(effects
				(font
					(size 1.27 1.27)
				)
				(justify mirror)
			)
		)
		(property "Value" ""
			(at 0 0 0)
			(layer "B.Fab")
			(effects
				(font
					(size 1.27 1.27)
				)
				(justify mirror)
			)
		)
		(duplicate_pad_numbers_are_jumpers no)
		(fp_line
			(start -0.7874 -0.4064)
			(end -0.7874 0.4064)
			(stroke
				(width 0.1524)
				(type default)
			)
			(layer "B.SilkS")
		)
		(fp_line
			(start -0.7874 0.4064)
			(end 0.7874 0.4064)
			(stroke
				(width 0.1524)
				(type default)
			)
			(layer "B.SilkS")
		)
		(fp_line
			(start 0.7874 -0.4064)
			(end -0.7874 -0.4064)
			(stroke
				(width 0.1524)
				(type default)
			)
			(layer "B.SilkS")
		)
		(fp_line
			(start 0.7874 0.4064)
			(end 0.7874 -0.4064)
			(stroke
				(width 0.1524)
				(type default)
			)
			(layer "B.SilkS")
		)
		(fp_line
			(start -0.67945 -0.3048)
			(end -0.67945 0.3048)
			(stroke
				(width 0.1)
				(type default)
			)
			(layer "B.Fab")
		)
		(fp_line
			(start -0.67945 0.3048)
			(end -0.120396 0.3048)
			(stroke
				(width 0.1)
				(type default)
			)
			(layer "B.Fab")
		)
		(fp_line
			(start -0.12065 -0.3048)
			(end -0.67945 -0.3048)
			(stroke
				(width 0.1)
				(type default)
			)
			(layer "B.Fab")
		)
		(fp_line
			(start -0.12065 -0.2794)
			(end -0.12065 -0.3048)
			(stroke
				(width 0.1)
				(type default)
			)
			(layer "B.Fab")
		)
		(fp_line
			(start -0.120396 0.2794)
			(end 0.12065 0.2794)
			(stroke
				(width 0.1)
				(type default)
			)
			(layer "B.Fab")
		)
		(fp_line
			(start -0.120396 0.3048)
			(end -0.120396 0.2794)
			(stroke
				(width 0.1)
				(type default)
			)
			(layer "B.Fab")
		)
		(fp_line
			(start 0.12065 -0.305054)
			(end 0.12065 -0.2794)
			(stroke
				(width 0.1)
				(type default)
			)
			(layer "B.Fab")
		)
		(fp_line
			(start 0.12065 -0.2794)
			(end -0.12065 -0.2794)
			(stroke
				(width 0.1)
				(type default)
			)
			(layer "B.Fab")
		)
		(fp_line
			(start 0.12065 0.2794)
			(end 0.12065 0.3048)
			(stroke
				(width 0.1)
				(type default)
			)
			(layer "B.Fab")
		)
		(fp_line
			(start 0.12065 0.3048)
			(end 0.67945 0.3048)
			(stroke
				(width 0.1)
				(type default)
			)
			(layer "B.Fab")
		)
		(fp_line
			(start 0.67945 -0.305054)
			(end 0.12065 -0.305054)
			(stroke
				(width 0.1)
				(type default)
			)
			(layer "B.Fab")
		)
		(fp_line
			(start 0.67945 0.3048)
			(end 0.67945 -0.305054)
			(stroke
				(width 0.1)
				(type default)
			)
			(layer "B.Fab")
		)
		(pad "1" smd circle
			(at 0.40005 0 180)
			(size 0 0)
			(layers "B.Cu" "B.Mask" "B.Paste")
			(net "PVDDCR_SOC_P0")
		)
		(pad "2" smd circle
			(at -0.40005 0 180)
			(size 0 0)
			(layers "B.Cu" "B.Mask" "B.Paste")
			(net "GND")
		)
	)
)
